FILE_TYPE = MACRO_DRAWING;
SET COLOR_WIRE YELLOW;
SET COLOR_PROP ORANGE;
SET COLOR_DOT WHITE;
SET COLOR_ARC YELLOW;
SET COLOR_BODY GREEN;
SET COLOR_NOTE PURPLE;
SET PROP_DISPLAY VALUE;
SET PAGE_NUMBER P404;
FORCEADD PT5161LRS..8
(-7875 3900);
FORCEPROP 1 LAST LOCATION U6011
J 0
(-8225 5525);
DISPLAY 0.723404 (-8225 5525);
PAINT GREEN (-8225 5525);
FORCEPROP 0 LAST $SEC 8
J 0
(-8225 5675);
DISPLAY 0.680851 (-8225 5675);
PAINT MONO (-8225 5675);
DISPLAY INVISIBLE (-8225 5675);
FORCEPROP 0 LAST CDS_SEC 8
J 0
(-8225 5675);
DISPLAY 0.680851 (-8225 5675);
DISPLAY INVISIBLE (-8225 5675);
FORCEPROP 0 LASTPIN (-7425 5050) $PN R35
J 0
(-7415 5060);
DISPLAY 0.680851 (-7415 5060);
PAINT MONO (-7415 5060);
FORCEPROP 0 LASTPIN (-7425 4700) $PN AB35
J 0
(-7415 4710);
DISPLAY 0.680851 (-7415 4710);
PAINT MONO (-7415 4710);
FORCEPROP 0 LASTPIN (-7425 4350) $PN AJ35
J 0
(-7415 4360);
DISPLAY 0.680851 (-7415 4360);
PAINT MONO (-7415 4360);
FORCEPROP 0 LASTPIN (-7425 4000) $PN AT35
J 0
(-7415 4010);
DISPLAY 0.680851 (-7415 4010);
PAINT MONO (-7415 4010);
FORCEPROP 0 LASTPIN (-7425 3650) $PN BC35
J 0
(-7415 3660);
DISPLAY 0.680851 (-7415 3660);
PAINT MONO (-7415 3660);
FORCEPROP 0 LASTPIN (-7425 3300) $PN BK35
J 0
(-7415 3310);
DISPLAY 0.680851 (-7415 3310);
PAINT MONO (-7415 3310);
FORCEPROP 0 LASTPIN (-7425 2950) $PN BU35
J 0
(-7415 2960);
DISPLAY 0.680851 (-7415 2960);
PAINT MONO (-7415 2960);
FORCEPROP 0 LASTPIN (-7425 2600) $PN CD35
J 0
(-7415 2610);
DISPLAY 0.680851 (-7415 2610);
PAINT MONO (-7415 2610);
FORCEPROP 0 LASTPIN (-7425 5150) $PN N34
J 0
(-7415 5160);
DISPLAY 0.680851 (-7415 5160);
PAINT MONO (-7415 5160);
FORCEPROP 0 LASTPIN (-7425 4800) $PN Y34
J 0
(-7415 4810);
DISPLAY 0.680851 (-7415 4810);
PAINT MONO (-7415 4810);
FORCEPROP 0 LASTPIN (-7425 4450) $PN AG34
J 0
(-7415 4460);
DISPLAY 0.680851 (-7415 4460);
PAINT MONO (-7415 4460);
FORCEPROP 0 LASTPIN (-7425 4100) $PN AP34
J 0
(-7415 4110);
DISPLAY 0.680851 (-7415 4110);
PAINT MONO (-7415 4110);
FORCEPROP 0 LASTPIN (-7425 3750) $PN BA34
J 0
(-7415 3760);
DISPLAY 0.680851 (-7415 3760);
PAINT MONO (-7415 3760);
FORCEPROP 0 LASTPIN (-7425 3400) $PN BH34
J 0
(-7415 3410);
DISPLAY 0.680851 (-7415 3410);
PAINT MONO (-7415 3410);
FORCEPROP 0 LASTPIN (-7425 3050) $PN BR34
J 0
(-7415 3060);
DISPLAY 0.680851 (-7415 3060);
PAINT MONO (-7415 3060);
FORCEPROP 0 LASTPIN (-7425 2700) $PN CB34
J 0
(-7415 2710);
DISPLAY 0.680851 (-7415 2710);
PAINT MONO (-7415 2710);
FORCEPROP 2 LAST PART_TYPE SMLF
J 0
(-8225 5625);
DISPLAY 0.680851 (-8225 5625);
FORCEPROP 2 LAST VALUE PT5161LRS
J 0
(-8225 5575);
DISPLAY 0.680851 (-8225 5575);
FORCEPROP 1 LAST MATERIAL IC
J 0
(-8225 5375);
DISPLAY 0.723404 (-8225 5375);
PAINT GREEN (-8225 5375);
FORCEPROP 2 LAST CDS_LIB pure_quanta
J 0
(-7875 3900);
DISPLAY INVISIBLE (-7875 3900);
FORCEPROP 1 LAST CDS_LMAN_SYM_OUTLINE -350,1450,300,-1400
J 0
(-7875 3900);
DISPLAY 0.468085 (-7875 3900);
PAINT GREEN (-7875 3900);
DISPLAY INVISIBLE (-7875 3900);
FORCEPROP 1 LAST NEEDS_NO_SIZE TRUE
J 0
(-7875 3900);
DISPLAY 0.723404 (-7875 3900);
PAINT GREEN (-7875 3900);
DISPLAY INVISIBLE (-7875 3900);
FORCEPROP 1 LAST PATH I1
J 0
(-7875 3900);
DISPLAY 0.723404 (-7875 3900);
PAINT GREEN (-7875 3900);
DISPLAY INVISIBLE (-7875 3900);
FORCEPROP 1 LAST PART_NUMBER AJ051610U03
J 0
(-8225 5450);
DISPLAY 0.723404 (-8225 5450);
PAINT GREEN (-8225 5450);
DISPLAY INVISIBLE (-8225 5450);
FORCEADD TAP..1
(-6850 4100);
FORCEPROP 3 LASTPIN (-6900 4100) SIG_NAME P5E_CPU0_P1_TX_C_DN<12>
J 0
(-6890 4110);
DISPLAY 0.659574 (-6890 4110);
PAINT MONO (-6890 4110);
DISPLAY INVISIBLE (-6890 4110);
FORCEPROP 1 LASTPIN (-6900 4100) BN 12
J 0
(-6912 4108);
DISPLAY 0.680851 (-6912 4108);
PAINT GREEN (-6912 4108);
FORCEPROP 2 LAST CDS_LIB standard
J 0
(-6850 4100);
DISPLAY INVISIBLE (-6850 4100);
FORCEPROP 1 LAST BODY_TYPE PLUMBING
J 0
(-6850 4150);
DISPLAY 0.872340 (-6850 4150);
PAINT GREEN (-6850 4150);
DISPLAY INVISIBLE (-6850 4150);
FORCEPROP 1 LAST HDL_TAP TRUE
J 0
(-6525 3975);
DISPLAY 0.872340 (-6525 3975);
DISPLAY INVISIBLE (-6525 3975);
FORCEPROP 1 LAST PATH I10
J 0
(-6852 4100);
DISPLAY 0.872340 (-6852 4100);
PAINT GREEN (-6852 4100);
DISPLAY INVISIBLE (-6852 4100);
FORCEADD TAP..1
(-6650 4000);
FORCEPROP 3 LASTPIN (-6700 4000) SIG_NAME P5E_CPU0_P1_TX_C_DP<12>
J 0
(-6690 4010);
DISPLAY 0.659574 (-6690 4010);
PAINT MONO (-6690 4010);
DISPLAY INVISIBLE (-6690 4010);
FORCEPROP 1 LASTPIN (-6700 4000) BN 12
J 0
(-6712 4008);
DISPLAY 0.680851 (-6712 4008);
PAINT GREEN (-6712 4008);
FORCEPROP 2 LAST CDS_LIB standard
J 0
(-6650 4000);
DISPLAY INVISIBLE (-6650 4000);
FORCEPROP 1 LAST BODY_TYPE PLUMBING
J 0
(-6650 4050);
DISPLAY 0.872340 (-6650 4050);
PAINT GREEN (-6650 4050);
DISPLAY INVISIBLE (-6650 4050);
FORCEPROP 1 LAST HDL_TAP TRUE
J 0
(-6325 3875);
DISPLAY 0.872340 (-6325 3875);
DISPLAY INVISIBLE (-6325 3875);
FORCEPROP 1 LAST PATH I11
J 0
(-6652 4000);
DISPLAY 0.872340 (-6652 4000);
PAINT GREEN (-6652 4000);
DISPLAY INVISIBLE (-6652 4000);
FORCEADD TAP..1
(-6850 4450);
FORCEPROP 3 LASTPIN (-6900 4450) SIG_NAME P5E_CPU0_P1_TX_C_DN<13>
J 0
(-6890 4460);
DISPLAY 0.659574 (-6890 4460);
PAINT MONO (-6890 4460);
DISPLAY INVISIBLE (-6890 4460);
FORCEPROP 1 LASTPIN (-6900 4450) BN 13
J 0
(-6912 4458);
DISPLAY 0.680851 (-6912 4458);
PAINT GREEN (-6912 4458);
FORCEPROP 2 LAST CDS_LIB standard
J 0
(-6850 4450);
DISPLAY INVISIBLE (-6850 4450);
FORCEPROP 1 LAST BODY_TYPE PLUMBING
J 0
(-6850 4500);
DISPLAY 0.872340 (-6850 4500);
PAINT GREEN (-6850 4500);
DISPLAY INVISIBLE (-6850 4500);
FORCEPROP 1 LAST HDL_TAP TRUE
J 0
(-6525 4325);
DISPLAY 0.872340 (-6525 4325);
DISPLAY INVISIBLE (-6525 4325);
FORCEPROP 1 LAST PATH I12
J 0
(-6852 4450);
DISPLAY 0.872340 (-6852 4450);
PAINT GREEN (-6852 4450);
DISPLAY INVISIBLE (-6852 4450);
FORCEADD TAP..1
(-6650 4350);
FORCEPROP 3 LASTPIN (-6700 4350) SIG_NAME P5E_CPU0_P1_TX_C_DP<13>
J 0
(-6690 4360);
DISPLAY 0.659574 (-6690 4360);
PAINT MONO (-6690 4360);
DISPLAY INVISIBLE (-6690 4360);
FORCEPROP 1 LASTPIN (-6700 4350) BN 13
J 0
(-6712 4358);
DISPLAY 0.680851 (-6712 4358);
PAINT GREEN (-6712 4358);
FORCEPROP 2 LAST CDS_LIB standard
J 0
(-6650 4350);
DISPLAY INVISIBLE (-6650 4350);
FORCEPROP 1 LAST BODY_TYPE PLUMBING
J 0
(-6650 4400);
DISPLAY 0.872340 (-6650 4400);
PAINT GREEN (-6650 4400);
DISPLAY INVISIBLE (-6650 4400);
FORCEPROP 1 LAST HDL_TAP TRUE
J 0
(-6325 4225);
DISPLAY 0.872340 (-6325 4225);
DISPLAY INVISIBLE (-6325 4225);
FORCEPROP 1 LAST PATH I13
J 0
(-6652 4350);
DISPLAY 0.872340 (-6652 4350);
PAINT GREEN (-6652 4350);
DISPLAY INVISIBLE (-6652 4350);
FORCEADD TAP..1
(-6650 4800);
FORCEPROP 3 LASTPIN (-6700 4800) SIG_NAME P5E_CPU0_P1_TX_C_DP<14>
J 0
(-6690 4810);
DISPLAY 0.659574 (-6690 4810);
PAINT MONO (-6690 4810);
DISPLAY INVISIBLE (-6690 4810);
FORCEPROP 1 LASTPIN (-6700 4800) BN 14
J 0
(-6712 4808);
DISPLAY 0.680851 (-6712 4808);
PAINT GREEN (-6712 4808);
FORCEPROP 2 LAST CDS_LIB standard
J 0
(-6650 4800);
DISPLAY INVISIBLE (-6650 4800);
FORCEPROP 1 LAST BODY_TYPE PLUMBING
J 0
(-6650 4850);
DISPLAY 0.872340 (-6650 4850);
PAINT GREEN (-6650 4850);
DISPLAY INVISIBLE (-6650 4850);
FORCEPROP 1 LAST HDL_TAP TRUE
J 0
(-6325 4675);
DISPLAY 0.872340 (-6325 4675);
DISPLAY INVISIBLE (-6325 4675);
FORCEPROP 1 LAST PATH I14
J 0
(-6652 4800);
DISPLAY 0.872340 (-6652 4800);
PAINT GREEN (-6652 4800);
DISPLAY INVISIBLE (-6652 4800);
FORCEADD TAP..1
(-6850 4700);
FORCEPROP 3 LASTPIN (-6900 4700) SIG_NAME P5E_CPU0_P1_TX_C_DN<14>
J 0
(-6890 4710);
DISPLAY 0.659574 (-6890 4710);
PAINT MONO (-6890 4710);
DISPLAY INVISIBLE (-6890 4710);
FORCEPROP 1 LASTPIN (-6900 4700) BN 14
J 0
(-6912 4708);
DISPLAY 0.680851 (-6912 4708);
PAINT GREEN (-6912 4708);
FORCEPROP 2 LAST CDS_LIB standard
J 0
(-6850 4700);
DISPLAY INVISIBLE (-6850 4700);
FORCEPROP 1 LAST BODY_TYPE PLUMBING
J 0
(-6850 4750);
DISPLAY 0.872340 (-6850 4750);
PAINT GREEN (-6850 4750);
DISPLAY INVISIBLE (-6850 4750);
FORCEPROP 1 LAST HDL_TAP TRUE
J 0
(-6525 4575);
DISPLAY 0.872340 (-6525 4575);
DISPLAY INVISIBLE (-6525 4575);
FORCEPROP 1 LAST PATH I15
J 0
(-6852 4700);
DISPLAY 0.872340 (-6852 4700);
PAINT GREEN (-6852 4700);
DISPLAY INVISIBLE (-6852 4700);
FORCEADD TAP..1
(-6850 5150);
FORCEPROP 3 LASTPIN (-6900 5150) SIG_NAME P5E_CPU0_P1_TX_C_DN<15>
J 0
(-6890 5160);
DISPLAY 0.659574 (-6890 5160);
PAINT MONO (-6890 5160);
DISPLAY INVISIBLE (-6890 5160);
FORCEPROP 1 LASTPIN (-6900 5150) BN 15
J 0
(-6912 5158);
DISPLAY 0.680851 (-6912 5158);
PAINT GREEN (-6912 5158);
FORCEPROP 2 LAST CDS_LIB standard
J 0
(-6850 5150);
DISPLAY INVISIBLE (-6850 5150);
FORCEPROP 1 LAST BODY_TYPE PLUMBING
J 0
(-6850 5200);
DISPLAY 0.872340 (-6850 5200);
PAINT GREEN (-6850 5200);
DISPLAY INVISIBLE (-6850 5200);
FORCEPROP 1 LAST HDL_TAP TRUE
J 0
(-6525 5025);
DISPLAY 0.872340 (-6525 5025);
DISPLAY INVISIBLE (-6525 5025);
FORCEPROP 1 LAST PATH I16
J 0
(-6852 5150);
DISPLAY 0.872340 (-6852 5150);
PAINT GREEN (-6852 5150);
DISPLAY INVISIBLE (-6852 5150);
FORCEADD TAP..1
(-6650 5050);
FORCEPROP 3 LASTPIN (-6700 5050) SIG_NAME P5E_CPU0_P1_TX_C_DP<15>
J 0
(-6690 5060);
DISPLAY 0.659574 (-6690 5060);
PAINT MONO (-6690 5060);
DISPLAY INVISIBLE (-6690 5060);
FORCEPROP 1 LASTPIN (-6700 5050) BN 15
J 0
(-6712 5058);
DISPLAY 0.680851 (-6712 5058);
PAINT GREEN (-6712 5058);
FORCEPROP 2 LAST CDS_LIB standard
J 0
(-6650 5050);
DISPLAY INVISIBLE (-6650 5050);
FORCEPROP 1 LAST BODY_TYPE PLUMBING
J 0
(-6650 5100);
DISPLAY 0.872340 (-6650 5100);
PAINT GREEN (-6650 5100);
DISPLAY INVISIBLE (-6650 5100);
FORCEPROP 1 LAST HDL_TAP TRUE
J 0
(-6325 4925);
DISPLAY 0.872340 (-6325 4925);
DISPLAY INVISIBLE (-6325 4925);
FORCEPROP 1 LAST PATH I17
J 0
(-6652 5050);
DISPLAY 0.872340 (-6652 5050);
PAINT GREEN (-6652 5050);
DISPLAY INVISIBLE (-6652 5050);
FORCEADD OFFPAGE..1
R 2
(-5650 5075);
FORCEPROP 2 LAST $XR0 63 
J 0
(-5464 5075);
DISPLAY 0.638298 (-5464 5075);
PAINT MONO (-5464 5075);
FORCEPROP 2 LAST CDS_LIB standard
J 0
(-5650 5075);
DISPLAY INVISIBLE (-5650 5075);
FORCEPROP 1 LAST OFFPAGE TRUE
J 2
(-5975 4950);
DISPLAY 0.872340 (-5975 4950);
DISPLAY INVISIBLE (-5975 4950);
FORCEPROP 1 LAST COMMENT_BODY TRUE
J 2
(-5775 4975);
DISPLAY 0.872340 (-5775 4975);
PAINT GREEN (-5775 4975);
DISPLAY INVISIBLE (-5775 4975);
FORCEPROP 2 LAST PATH I18
J 0
(-5475 5150);
DISPLAY 0.680851 (-5475 5150);
DISPLAY INVISIBLE (-5475 5150);
FORCEADD OFFPAGE..1
R 2
(-5650 5175);
FORCEPROP 2 LAST $XR0 63 
J 0
(-5464 5175);
DISPLAY 0.638298 (-5464 5175);
PAINT MONO (-5464 5175);
FORCEPROP 2 LAST CDS_LIB standard
J 2
(-5650 5175);
DISPLAY INVISIBLE (-5650 5175);
FORCEPROP 1 LAST OFFPAGE TRUE
J 2
(-5975 5050);
DISPLAY 0.872340 (-5975 5050);
DISPLAY INVISIBLE (-5975 5050);
FORCEPROP 1 LAST COMMENT_BODY TRUE
J 2
(-5775 5075);
DISPLAY 0.872340 (-5775 5075);
PAINT GREEN (-5775 5075);
DISPLAY INVISIBLE (-5775 5075);
FORCEPROP 2 LAST PATH I19
J 0
(-5475 5250);
DISPLAY 0.680851 (-5475 5250);
DISPLAY INVISIBLE (-5475 5250);
FORCEADD TAP..1
(-6650 2600);
FORCEPROP 3 LASTPIN (-6700 2600) SIG_NAME P5E_CPU0_P1_TX_C_DP<8>
J 0
(-6690 2610);
DISPLAY 0.659574 (-6690 2610);
PAINT MONO (-6690 2610);
DISPLAY INVISIBLE (-6690 2610);
FORCEPROP 1 LASTPIN (-6700 2600) BN 8
J 0
(-6712 2608);
DISPLAY 0.680851 (-6712 2608);
PAINT GREEN (-6712 2608);
FORCEPROP 2 LAST CDS_LIB standard
J 0
(-6650 2600);
DISPLAY INVISIBLE (-6650 2600);
FORCEPROP 1 LAST BODY_TYPE PLUMBING
J 0
(-6650 2650);
DISPLAY 0.872340 (-6650 2650);
PAINT GREEN (-6650 2650);
DISPLAY INVISIBLE (-6650 2650);
FORCEPROP 1 LAST HDL_TAP TRUE
J 0
(-6325 2475);
DISPLAY 0.872340 (-6325 2475);
DISPLAY INVISIBLE (-6325 2475);
FORCEPROP 1 LAST PATH I2
J 0
(-6652 2600);
DISPLAY 0.872340 (-6652 2600);
PAINT GREEN (-6652 2600);
DISPLAY INVISIBLE (-6652 2600);
FORCEADD TAP..1
(-2225 2650);
FORCEPROP 3 LASTPIN (-2275 2650) SIG_NAME P5E_CPU0_P1_TX_C_DN<0>
J 0
(-2265 2660);
DISPLAY 0.659574 (-2265 2660);
PAINT MONO (-2265 2660);
DISPLAY INVISIBLE (-2265 2660);
FORCEPROP 1 LASTPIN (-2275 2650) BN 0
J 0
(-2287 2658);
DISPLAY 0.680851 (-2287 2658);
PAINT GREEN (-2287 2658);
FORCEPROP 2 LAST CDS_LIB standard
J 0
(-2225 2650);
DISPLAY INVISIBLE (-2225 2650);
FORCEPROP 1 LAST BODY_TYPE PLUMBING
J 0
(-2225 2700);
DISPLAY 0.872340 (-2225 2700);
PAINT GREEN (-2225 2700);
DISPLAY INVISIBLE (-2225 2700);
FORCEPROP 1 LAST HDL_TAP TRUE
J 0
(-1900 2525);
DISPLAY 0.872340 (-1900 2525);
DISPLAY INVISIBLE (-1900 2525);
FORCEPROP 1 LAST PATH I20
J 0
(-2227 2650);
DISPLAY 0.872340 (-2227 2650);
PAINT GREEN (-2227 2650);
DISPLAY INVISIBLE (-2227 2650);
FORCEADD TAP..1
(-2025 2550);
FORCEPROP 3 LASTPIN (-2075 2550) SIG_NAME P5E_CPU0_P1_TX_C_DP<0>
J 0
(-2065 2560);
DISPLAY 0.659574 (-2065 2560);
PAINT MONO (-2065 2560);
DISPLAY INVISIBLE (-2065 2560);
FORCEPROP 1 LASTPIN (-2075 2550) BN 0
J 0
(-2087 2558);
DISPLAY 0.680851 (-2087 2558);
PAINT GREEN (-2087 2558);
FORCEPROP 2 LAST CDS_LIB standard
J 0
(-2025 2550);
DISPLAY INVISIBLE (-2025 2550);
FORCEPROP 1 LAST BODY_TYPE PLUMBING
J 0
(-2025 2600);
DISPLAY 0.872340 (-2025 2600);
PAINT GREEN (-2025 2600);
DISPLAY INVISIBLE (-2025 2600);
FORCEPROP 1 LAST HDL_TAP TRUE
J 0
(-1700 2425);
DISPLAY 0.872340 (-1700 2425);
DISPLAY INVISIBLE (-1700 2425);
FORCEPROP 1 LAST PATH I21
J 0
(-2027 2550);
DISPLAY 0.872340 (-2027 2550);
PAINT GREEN (-2027 2550);
DISPLAY INVISIBLE (-2027 2550);
FORCEADD TAP..1
(-2225 2900);
FORCEPROP 3 LASTPIN (-2275 2900) SIG_NAME P5E_CPU0_P1_TX_C_DN<1>
J 0
(-2265 2910);
DISPLAY 0.659574 (-2265 2910);
PAINT MONO (-2265 2910);
DISPLAY INVISIBLE (-2265 2910);
FORCEPROP 1 LASTPIN (-2275 2900) BN 1
J 0
(-2287 2908);
DISPLAY 0.680851 (-2287 2908);
PAINT GREEN (-2287 2908);
FORCEPROP 2 LAST CDS_LIB standard
J 0
(-2225 2900);
DISPLAY INVISIBLE (-2225 2900);
FORCEPROP 1 LAST BODY_TYPE PLUMBING
J 0
(-2225 2950);
DISPLAY 0.872340 (-2225 2950);
PAINT GREEN (-2225 2950);
DISPLAY INVISIBLE (-2225 2950);
FORCEPROP 1 LAST HDL_TAP TRUE
J 0
(-1900 2775);
DISPLAY 0.872340 (-1900 2775);
DISPLAY INVISIBLE (-1900 2775);
FORCEPROP 1 LAST PATH I22
J 0
(-2227 2900);
DISPLAY 0.872340 (-2227 2900);
PAINT GREEN (-2227 2900);
DISPLAY INVISIBLE (-2227 2900);
FORCEADD TAP..1
(-2025 3000);
FORCEPROP 3 LASTPIN (-2075 3000) SIG_NAME P5E_CPU0_P1_TX_C_DP<1>
J 0
(-2065 3010);
DISPLAY 0.659574 (-2065 3010);
PAINT MONO (-2065 3010);
DISPLAY INVISIBLE (-2065 3010);
FORCEPROP 1 LASTPIN (-2075 3000) BN 1
J 0
(-2087 3008);
DISPLAY 0.680851 (-2087 3008);
PAINT GREEN (-2087 3008);
FORCEPROP 2 LAST CDS_LIB standard
J 0
(-2025 3000);
DISPLAY INVISIBLE (-2025 3000);
FORCEPROP 1 LAST BODY_TYPE PLUMBING
J 0
(-2025 3050);
DISPLAY 0.872340 (-2025 3050);
PAINT GREEN (-2025 3050);
DISPLAY INVISIBLE (-2025 3050);
FORCEPROP 1 LAST HDL_TAP TRUE
J 0
(-1700 2875);
DISPLAY 0.872340 (-1700 2875);
DISPLAY INVISIBLE (-1700 2875);
FORCEPROP 1 LAST PATH I23
J 0
(-2027 3000);
DISPLAY 0.872340 (-2027 3000);
PAINT GREEN (-2027 3000);
DISPLAY INVISIBLE (-2027 3000);
FORCEADD TAP..1
(-2225 3350);
FORCEPROP 3 LASTPIN (-2275 3350) SIG_NAME P5E_CPU0_P1_TX_C_DN<2>
J 0
(-2265 3360);
DISPLAY 0.659574 (-2265 3360);
PAINT MONO (-2265 3360);
DISPLAY INVISIBLE (-2265 3360);
FORCEPROP 1 LASTPIN (-2275 3350) BN 2
J 0
(-2287 3358);
DISPLAY 0.680851 (-2287 3358);
PAINT GREEN (-2287 3358);
FORCEPROP 2 LAST CDS_LIB standard
J 0
(-2225 3350);
DISPLAY INVISIBLE (-2225 3350);
FORCEPROP 1 LAST BODY_TYPE PLUMBING
J 0
(-2225 3400);
DISPLAY 0.872340 (-2225 3400);
PAINT GREEN (-2225 3400);
DISPLAY INVISIBLE (-2225 3400);
FORCEPROP 1 LAST HDL_TAP TRUE
J 0
(-1900 3225);
DISPLAY 0.872340 (-1900 3225);
DISPLAY INVISIBLE (-1900 3225);
FORCEPROP 1 LAST PATH I24
J 0
(-2227 3350);
DISPLAY 0.872340 (-2227 3350);
PAINT GREEN (-2227 3350);
DISPLAY INVISIBLE (-2227 3350);
FORCEADD TAP..1
(-2225 3700);
FORCEPROP 3 LASTPIN (-2275 3700) SIG_NAME P5E_CPU0_P1_TX_C_DN<3>
J 0
(-2265 3710);
DISPLAY 0.659574 (-2265 3710);
PAINT MONO (-2265 3710);
DISPLAY INVISIBLE (-2265 3710);
FORCEPROP 1 LASTPIN (-2275 3700) BN 3
J 0
(-2287 3708);
DISPLAY 0.680851 (-2287 3708);
PAINT GREEN (-2287 3708);
FORCEPROP 2 LAST CDS_LIB standard
J 0
(-2225 3700);
DISPLAY INVISIBLE (-2225 3700);
FORCEPROP 1 LAST BODY_TYPE PLUMBING
J 0
(-2225 3750);
DISPLAY 0.872340 (-2225 3750);
PAINT GREEN (-2225 3750);
DISPLAY INVISIBLE (-2225 3750);
FORCEPROP 1 LAST HDL_TAP TRUE
J 0
(-1900 3575);
DISPLAY 0.872340 (-1900 3575);
DISPLAY INVISIBLE (-1900 3575);
FORCEPROP 1 LAST PATH I25
J 0
(-2227 3700);
DISPLAY 0.872340 (-2227 3700);
PAINT GREEN (-2227 3700);
DISPLAY INVISIBLE (-2227 3700);
FORCEADD TAP..1
(-2025 3250);
FORCEPROP 3 LASTPIN (-2075 3250) SIG_NAME P5E_CPU0_P1_TX_C_DP<2>
J 0
(-2065 3260);
DISPLAY 0.659574 (-2065 3260);
PAINT MONO (-2065 3260);
DISPLAY INVISIBLE (-2065 3260);
FORCEPROP 1 LASTPIN (-2075 3250) BN 2
J 0
(-2087 3258);
DISPLAY 0.680851 (-2087 3258);
PAINT GREEN (-2087 3258);
FORCEPROP 2 LAST CDS_LIB standard
J 0
(-2025 3250);
DISPLAY INVISIBLE (-2025 3250);
FORCEPROP 1 LAST BODY_TYPE PLUMBING
J 0
(-2025 3300);
DISPLAY 0.872340 (-2025 3300);
PAINT GREEN (-2025 3300);
DISPLAY INVISIBLE (-2025 3300);
FORCEPROP 1 LAST HDL_TAP TRUE
J 0
(-1700 3125);
DISPLAY 0.872340 (-1700 3125);
DISPLAY INVISIBLE (-1700 3125);
FORCEPROP 1 LAST PATH I26
J 0
(-2027 3250);
DISPLAY 0.872340 (-2027 3250);
PAINT GREEN (-2027 3250);
DISPLAY INVISIBLE (-2027 3250);
FORCEADD TAP..1
(-2025 3600);
FORCEPROP 3 LASTPIN (-2075 3600) SIG_NAME P5E_CPU0_P1_TX_C_DP<3>
J 0
(-2065 3610);
DISPLAY 0.659574 (-2065 3610);
PAINT MONO (-2065 3610);
DISPLAY INVISIBLE (-2065 3610);
FORCEPROP 1 LASTPIN (-2075 3600) BN 3
J 0
(-2087 3608);
DISPLAY 0.680851 (-2087 3608);
PAINT GREEN (-2087 3608);
FORCEPROP 2 LAST CDS_LIB standard
J 0
(-2025 3600);
DISPLAY INVISIBLE (-2025 3600);
FORCEPROP 1 LAST BODY_TYPE PLUMBING
J 0
(-2025 3650);
DISPLAY 0.872340 (-2025 3650);
PAINT GREEN (-2025 3650);
DISPLAY INVISIBLE (-2025 3650);
FORCEPROP 1 LAST HDL_TAP TRUE
J 0
(-1700 3475);
DISPLAY 0.872340 (-1700 3475);
DISPLAY INVISIBLE (-1700 3475);
FORCEPROP 1 LAST PATH I27
J 0
(-2027 3600);
DISPLAY 0.872340 (-2027 3600);
PAINT GREEN (-2027 3600);
DISPLAY INVISIBLE (-2027 3600);
FORCEADD TAP..1
(-2225 4050);
FORCEPROP 3 LASTPIN (-2275 4050) SIG_NAME P5E_CPU0_P1_TX_C_DN<4>
J 0
(-2265 4060);
DISPLAY 0.659574 (-2265 4060);
PAINT MONO (-2265 4060);
DISPLAY INVISIBLE (-2265 4060);
FORCEPROP 1 LASTPIN (-2275 4050) BN 4
J 0
(-2287 4058);
DISPLAY 0.680851 (-2287 4058);
PAINT GREEN (-2287 4058);
FORCEPROP 2 LAST CDS_LIB standard
J 0
(-2225 4050);
DISPLAY INVISIBLE (-2225 4050);
FORCEPROP 1 LAST BODY_TYPE PLUMBING
J 0
(-2225 4100);
DISPLAY 0.872340 (-2225 4100);
PAINT GREEN (-2225 4100);
DISPLAY INVISIBLE (-2225 4100);
FORCEPROP 1 LAST HDL_TAP TRUE
J 0
(-1900 3925);
DISPLAY 0.872340 (-1900 3925);
DISPLAY INVISIBLE (-1900 3925);
FORCEPROP 1 LAST PATH I28
J 0
(-2227 4050);
DISPLAY 0.872340 (-2227 4050);
PAINT GREEN (-2227 4050);
DISPLAY INVISIBLE (-2227 4050);
FORCEADD TAP..1
(-2025 3950);
FORCEPROP 3 LASTPIN (-2075 3950) SIG_NAME P5E_CPU0_P1_TX_C_DP<4>
J 0
(-2065 3960);
DISPLAY 0.659574 (-2065 3960);
PAINT MONO (-2065 3960);
DISPLAY INVISIBLE (-2065 3960);
FORCEPROP 1 LASTPIN (-2075 3950) BN 4
J 0
(-2087 3958);
DISPLAY 0.680851 (-2087 3958);
PAINT GREEN (-2087 3958);
FORCEPROP 2 LAST CDS_LIB standard
J 0
(-2025 3950);
DISPLAY INVISIBLE (-2025 3950);
FORCEPROP 1 LAST BODY_TYPE PLUMBING
J 0
(-2025 4000);
DISPLAY 0.872340 (-2025 4000);
PAINT GREEN (-2025 4000);
DISPLAY INVISIBLE (-2025 4000);
FORCEPROP 1 LAST HDL_TAP TRUE
J 0
(-1700 3825);
DISPLAY 0.872340 (-1700 3825);
DISPLAY INVISIBLE (-1700 3825);
FORCEPROP 1 LAST PATH I29
J 0
(-2027 3950);
DISPLAY 0.872340 (-2027 3950);
PAINT GREEN (-2027 3950);
DISPLAY INVISIBLE (-2027 3950);
FORCEADD TAP..1
(-6850 2700);
FORCEPROP 3 LASTPIN (-6900 2700) SIG_NAME P5E_CPU0_P1_TX_C_DN<8>
J 0
(-6890 2710);
DISPLAY 0.659574 (-6890 2710);
PAINT MONO (-6890 2710);
DISPLAY INVISIBLE (-6890 2710);
FORCEPROP 1 LASTPIN (-6900 2700) BN 8
J 0
(-6912 2708);
DISPLAY 0.680851 (-6912 2708);
PAINT GREEN (-6912 2708);
FORCEPROP 2 LAST CDS_LIB standard
J 0
(-6850 2700);
DISPLAY INVISIBLE (-6850 2700);
FORCEPROP 1 LAST BODY_TYPE PLUMBING
J 0
(-6850 2750);
DISPLAY 0.872340 (-6850 2750);
PAINT GREEN (-6850 2750);
DISPLAY INVISIBLE (-6850 2750);
FORCEPROP 1 LAST HDL_TAP TRUE
J 0
(-6525 2575);
DISPLAY 0.872340 (-6525 2575);
DISPLAY INVISIBLE (-6525 2575);
FORCEPROP 1 LAST PATH I3
J 0
(-6852 2700);
DISPLAY 0.872340 (-6852 2700);
PAINT GREEN (-6852 2700);
DISPLAY INVISIBLE (-6852 2700);
FORCEADD TAP..1
(-2225 4400);
FORCEPROP 3 LASTPIN (-2275 4400) SIG_NAME P5E_CPU0_P1_TX_C_DN<5>
J 0
(-2265 4410);
DISPLAY 0.659574 (-2265 4410);
PAINT MONO (-2265 4410);
DISPLAY INVISIBLE (-2265 4410);
FORCEPROP 1 LASTPIN (-2275 4400) BN 5
J 0
(-2287 4408);
DISPLAY 0.680851 (-2287 4408);
PAINT GREEN (-2287 4408);
FORCEPROP 2 LAST CDS_LIB standard
J 0
(-2225 4400);
DISPLAY INVISIBLE (-2225 4400);
FORCEPROP 1 LAST BODY_TYPE PLUMBING
J 0
(-2225 4450);
DISPLAY 0.872340 (-2225 4450);
PAINT GREEN (-2225 4450);
DISPLAY INVISIBLE (-2225 4450);
FORCEPROP 1 LAST HDL_TAP TRUE
J 0
(-1900 4275);
DISPLAY 0.872340 (-1900 4275);
DISPLAY INVISIBLE (-1900 4275);
FORCEPROP 1 LAST PATH I30
J 0
(-2227 4400);
DISPLAY 0.872340 (-2227 4400);
PAINT GREEN (-2227 4400);
DISPLAY INVISIBLE (-2227 4400);
FORCEADD TAP..1
(-2025 4300);
FORCEPROP 3 LASTPIN (-2075 4300) SIG_NAME P5E_CPU0_P1_TX_C_DP<5>
J 0
(-2065 4310);
DISPLAY 0.659574 (-2065 4310);
PAINT MONO (-2065 4310);
DISPLAY INVISIBLE (-2065 4310);
FORCEPROP 1 LASTPIN (-2075 4300) BN 5
J 0
(-2087 4308);
DISPLAY 0.680851 (-2087 4308);
PAINT GREEN (-2087 4308);
FORCEPROP 2 LAST CDS_LIB standard
J 0
(-2025 4300);
DISPLAY INVISIBLE (-2025 4300);
FORCEPROP 1 LAST BODY_TYPE PLUMBING
J 0
(-2025 4350);
DISPLAY 0.872340 (-2025 4350);
PAINT GREEN (-2025 4350);
DISPLAY INVISIBLE (-2025 4350);
FORCEPROP 1 LAST HDL_TAP TRUE
J 0
(-1700 4175);
DISPLAY 0.872340 (-1700 4175);
DISPLAY INVISIBLE (-1700 4175);
FORCEPROP 1 LAST PATH I31
J 0
(-2027 4300);
DISPLAY 0.872340 (-2027 4300);
PAINT GREEN (-2027 4300);
DISPLAY INVISIBLE (-2027 4300);
FORCEADD TAP..1
(-2025 4650);
FORCEPROP 3 LASTPIN (-2075 4650) SIG_NAME P5E_CPU0_P1_TX_C_DP<6>
J 0
(-2065 4660);
DISPLAY 0.659574 (-2065 4660);
PAINT MONO (-2065 4660);
DISPLAY INVISIBLE (-2065 4660);
FORCEPROP 1 LASTPIN (-2075 4650) BN 6
J 0
(-2087 4658);
DISPLAY 0.680851 (-2087 4658);
PAINT GREEN (-2087 4658);
FORCEPROP 2 LAST CDS_LIB standard
J 0
(-2025 4650);
DISPLAY INVISIBLE (-2025 4650);
FORCEPROP 1 LAST BODY_TYPE PLUMBING
J 0
(-2025 4700);
DISPLAY 0.872340 (-2025 4700);
PAINT GREEN (-2025 4700);
DISPLAY INVISIBLE (-2025 4700);
FORCEPROP 1 LAST HDL_TAP TRUE
J 0
(-1700 4525);
DISPLAY 0.872340 (-1700 4525);
DISPLAY INVISIBLE (-1700 4525);
FORCEPROP 1 LAST PATH I32
J 0
(-2027 4650);
DISPLAY 0.872340 (-2027 4650);
PAINT GREEN (-2027 4650);
DISPLAY INVISIBLE (-2027 4650);
FORCEADD TAP..1
(-2225 4750);
FORCEPROP 3 LASTPIN (-2275 4750) SIG_NAME P5E_CPU0_P1_TX_C_DN<6>
J 0
(-2265 4760);
DISPLAY 0.659574 (-2265 4760);
PAINT MONO (-2265 4760);
DISPLAY INVISIBLE (-2265 4760);
FORCEPROP 1 LASTPIN (-2275 4750) BN 6
J 0
(-2287 4758);
DISPLAY 0.680851 (-2287 4758);
PAINT GREEN (-2287 4758);
FORCEPROP 2 LAST CDS_LIB standard
J 0
(-2225 4750);
DISPLAY INVISIBLE (-2225 4750);
FORCEPROP 1 LAST BODY_TYPE PLUMBING
J 0
(-2225 4800);
DISPLAY 0.872340 (-2225 4800);
PAINT GREEN (-2225 4800);
DISPLAY INVISIBLE (-2225 4800);
FORCEPROP 1 LAST HDL_TAP TRUE
J 0
(-1900 4625);
DISPLAY 0.872340 (-1900 4625);
DISPLAY INVISIBLE (-1900 4625);
FORCEPROP 1 LAST PATH I33
J 0
(-2227 4750);
DISPLAY 0.872340 (-2227 4750);
PAINT GREEN (-2227 4750);
DISPLAY INVISIBLE (-2227 4750);
FORCEADD TAP..1
(-2225 5100);
FORCEPROP 3 LASTPIN (-2275 5100) SIG_NAME P5E_CPU0_P1_TX_C_DN<7>
J 0
(-2265 5110);
DISPLAY 0.659574 (-2265 5110);
PAINT MONO (-2265 5110);
DISPLAY INVISIBLE (-2265 5110);
FORCEPROP 1 LASTPIN (-2275 5100) BN 7
J 0
(-2287 5108);
DISPLAY 0.680851 (-2287 5108);
PAINT GREEN (-2287 5108);
FORCEPROP 2 LAST CDS_LIB standard
J 0
(-2225 5100);
DISPLAY INVISIBLE (-2225 5100);
FORCEPROP 1 LAST BODY_TYPE PLUMBING
J 0
(-2225 5150);
DISPLAY 0.872340 (-2225 5150);
PAINT GREEN (-2225 5150);
DISPLAY INVISIBLE (-2225 5150);
FORCEPROP 1 LAST HDL_TAP TRUE
J 0
(-1900 4975);
DISPLAY 0.872340 (-1900 4975);
DISPLAY INVISIBLE (-1900 4975);
FORCEPROP 1 LAST PATH I34
J 0
(-2227 5100);
DISPLAY 0.872340 (-2227 5100);
PAINT GREEN (-2227 5100);
DISPLAY INVISIBLE (-2227 5100);
FORCEADD TAP..1
(-2025 5000);
FORCEPROP 3 LASTPIN (-2075 5000) SIG_NAME P5E_CPU0_P1_TX_C_DP<7>
J 0
(-2065 5010);
DISPLAY 0.659574 (-2065 5010);
PAINT MONO (-2065 5010);
DISPLAY INVISIBLE (-2065 5010);
FORCEPROP 1 LASTPIN (-2075 5000) BN 7
J 0
(-2087 5008);
DISPLAY 0.680851 (-2087 5008);
PAINT GREEN (-2087 5008);
FORCEPROP 2 LAST CDS_LIB standard
J 0
(-2025 5000);
DISPLAY INVISIBLE (-2025 5000);
FORCEPROP 1 LAST BODY_TYPE PLUMBING
J 0
(-2025 5050);
DISPLAY 0.872340 (-2025 5050);
PAINT GREEN (-2025 5050);
DISPLAY INVISIBLE (-2025 5050);
FORCEPROP 1 LAST HDL_TAP TRUE
J 0
(-1700 4875);
DISPLAY 0.872340 (-1700 4875);
DISPLAY INVISIBLE (-1700 4875);
FORCEPROP 1 LAST PATH I35
J 0
(-2027 5000);
DISPLAY 0.872340 (-2027 5000);
PAINT GREEN (-2027 5000);
DISPLAY INVISIBLE (-2027 5000);
FORCEADD OFFPAGE..1
R 2
(-1025 5025);
FORCEPROP 2 LAST $XR0 63 
J 0
(-839 5025);
DISPLAY 0.638298 (-839 5025);
PAINT MONO (-839 5025);
FORCEPROP 2 LAST CDS_LIB standard
J 0
(-1025 5025);
DISPLAY INVISIBLE (-1025 5025);
FORCEPROP 1 LAST OFFPAGE TRUE
J 2
(-1350 4900);
DISPLAY 0.872340 (-1350 4900);
DISPLAY INVISIBLE (-1350 4900);
FORCEPROP 1 LAST COMMENT_BODY TRUE
J 2
(-1150 4925);
DISPLAY 0.872340 (-1150 4925);
PAINT GREEN (-1150 4925);
DISPLAY INVISIBLE (-1150 4925);
FORCEPROP 2 LAST PATH I36
J 0
(-850 5100);
DISPLAY 0.680851 (-850 5100);
DISPLAY INVISIBLE (-850 5100);
FORCEADD OFFPAGE..1
R 2
(-1025 5125);
FORCEPROP 2 LAST $XR0 63 
J 0
(-839 5125);
DISPLAY 0.638298 (-839 5125);
PAINT MONO (-839 5125);
FORCEPROP 2 LAST CDS_LIB standard
J 2
(-1025 5125);
DISPLAY INVISIBLE (-1025 5125);
FORCEPROP 1 LAST OFFPAGE TRUE
J 2
(-1350 5000);
DISPLAY 0.872340 (-1350 5000);
DISPLAY INVISIBLE (-1350 5000);
FORCEPROP 1 LAST COMMENT_BODY TRUE
J 2
(-1150 5025);
DISPLAY 0.872340 (-1150 5025);
PAINT GREEN (-1150 5025);
DISPLAY INVISIBLE (-1150 5025);
FORCEPROP 2 LAST PATH I37
J 0
(-850 5200);
DISPLAY 0.680851 (-850 5200);
DISPLAY INVISIBLE (-850 5200);
FORCEADD PT5161LRS..9
(-3250 3850);
FORCEPROP 1 LAST LOCATION U6011
J 0
(-3600 5475);
DISPLAY 0.723404 (-3600 5475);
PAINT GREEN (-3600 5475);
FORCEPROP 0 LAST $SEC 9
J 0
(-3600 5625);
DISPLAY 0.680851 (-3600 5625);
PAINT MONO (-3600 5625);
DISPLAY INVISIBLE (-3600 5625);
FORCEPROP 0 LAST CDS_SEC 9
J 0
(-3600 5625);
DISPLAY 0.680851 (-3600 5625);
DISPLAY INVISIBLE (-3600 5625);
FORCEPROP 0 LASTPIN (-2800 5000) $PN CL35
J 0
(-2790 5010);
DISPLAY 0.680851 (-2790 5010);
PAINT MONO (-2790 5010);
FORCEPROP 0 LASTPIN (-2800 4650) $PN CV35
J 0
(-2790 4660);
DISPLAY 0.680851 (-2790 4660);
PAINT MONO (-2790 4660);
FORCEPROP 0 LASTPIN (-2800 4300) $PN DE35
J 0
(-2790 4310);
DISPLAY 0.680851 (-2790 4310);
PAINT MONO (-2790 4310);
FORCEPROP 0 LASTPIN (-2800 3950) $PN DM35
J 0
(-2790 3960);
DISPLAY 0.680851 (-2790 3960);
PAINT MONO (-2790 3960);
FORCEPROP 0 LASTPIN (-2800 3600) $PN DW35
J 0
(-2790 3610);
DISPLAY 0.680851 (-2790 3610);
PAINT MONO (-2790 3610);
FORCEPROP 0 LASTPIN (-2800 3250) $PN EF35
J 0
(-2790 3260);
DISPLAY 0.680851 (-2790 3260);
PAINT MONO (-2790 3260);
FORCEPROP 0 LASTPIN (-2800 2900) $PN EN35
J 0
(-2790 2910);
DISPLAY 0.680851 (-2790 2910);
PAINT MONO (-2790 2910);
FORCEPROP 0 LASTPIN (-2800 2550) $PN EY35
J 0
(-2790 2560);
DISPLAY 0.680851 (-2790 2560);
PAINT MONO (-2790 2560);
FORCEPROP 0 LASTPIN (-2800 5100) $PN CJ34
J 0
(-2790 5110);
DISPLAY 0.680851 (-2790 5110);
PAINT MONO (-2790 5110);
FORCEPROP 0 LASTPIN (-2800 4750) $PN CT34
J 0
(-2790 4760);
DISPLAY 0.680851 (-2790 4760);
PAINT MONO (-2790 4760);
FORCEPROP 0 LASTPIN (-2800 4400) $PN DC34
J 0
(-2790 4410);
DISPLAY 0.680851 (-2790 4410);
PAINT MONO (-2790 4410);
FORCEPROP 0 LASTPIN (-2800 4050) $PN DK34
J 0
(-2790 4060);
DISPLAY 0.680851 (-2790 4060);
PAINT MONO (-2790 4060);
FORCEPROP 0 LASTPIN (-2800 3700) $PN DU34
J 0
(-2790 3710);
DISPLAY 0.680851 (-2790 3710);
PAINT MONO (-2790 3710);
FORCEPROP 0 LASTPIN (-2800 3350) $PN ED34
J 0
(-2790 3360);
DISPLAY 0.680851 (-2790 3360);
PAINT MONO (-2790 3360);
FORCEPROP 0 LASTPIN (-2800 3000) $PN EL34
J 0
(-2790 3010);
DISPLAY 0.680851 (-2790 3010);
PAINT MONO (-2790 3010);
FORCEPROP 0 LASTPIN (-2800 2650) $PN EV34
J 0
(-2790 2660);
DISPLAY 0.680851 (-2790 2660);
PAINT MONO (-2790 2660);
FORCEPROP 1 LAST MATERIAL IC
J 0
(-3600 5325);
DISPLAY 0.723404 (-3600 5325);
PAINT GREEN (-3600 5325);
FORCEPROP 2 LAST VALUE PT5161LRS
J 0
(-3600 5525);
DISPLAY 0.680851 (-3600 5525);
FORCEPROP 2 LAST PART_TYPE SMLF
J 0
(-3600 5575);
DISPLAY 0.680851 (-3600 5575);
FORCEPROP 1 LAST NEEDS_NO_SIZE TRUE
J 0
(-3250 3850);
DISPLAY 0.723404 (-3250 3850);
PAINT GREEN (-3250 3850);
DISPLAY INVISIBLE (-3250 3850);
FORCEPROP 1 LAST CDS_LMAN_SYM_OUTLINE -350,1450,300,-1400
J 0
(-3250 3850);
DISPLAY 0.468085 (-3250 3850);
PAINT GREEN (-3250 3850);
DISPLAY INVISIBLE (-3250 3850);
FORCEPROP 2 LAST CDS_LIB pure_quanta
J 0
(-3250 3850);
DISPLAY INVISIBLE (-3250 3850);
FORCEPROP 1 LAST PATH I38
J 0
(-3250 3850);
DISPLAY 0.723404 (-3250 3850);
PAINT GREEN (-3250 3850);
DISPLAY INVISIBLE (-3250 3850);
FORCEPROP 1 LAST PART_NUMBER AJ051610U03
J 0
(-3600 5400);
DISPLAY 0.723404 (-3600 5400);
PAINT GREEN (-3600 5400);
DISPLAY INVISIBLE (-3600 5400);
FORCEADD TAP..1
(-6850 3050);
FORCEPROP 3 LASTPIN (-6900 3050) SIG_NAME P5E_CPU0_P1_TX_C_DN<9>
J 0
(-6890 3060);
DISPLAY 0.659574 (-6890 3060);
PAINT MONO (-6890 3060);
DISPLAY INVISIBLE (-6890 3060);
FORCEPROP 1 LASTPIN (-6900 3050) BN 9
J 0
(-6912 3058);
DISPLAY 0.680851 (-6912 3058);
PAINT GREEN (-6912 3058);
FORCEPROP 2 LAST CDS_LIB standard
J 0
(-6850 3050);
DISPLAY INVISIBLE (-6850 3050);
FORCEPROP 1 LAST BODY_TYPE PLUMBING
J 0
(-6850 3100);
DISPLAY 0.872340 (-6850 3100);
PAINT GREEN (-6850 3100);
DISPLAY INVISIBLE (-6850 3100);
FORCEPROP 1 LAST HDL_TAP TRUE
J 0
(-6525 2925);
DISPLAY 0.872340 (-6525 2925);
DISPLAY INVISIBLE (-6525 2925);
FORCEPROP 1 LAST PATH I4
J 0
(-6852 3050);
DISPLAY 0.872340 (-6852 3050);
PAINT GREEN (-6852 3050);
DISPLAY INVISIBLE (-6852 3050);
FORCEADD TAP..1
(-6650 2950);
FORCEPROP 3 LASTPIN (-6700 2950) SIG_NAME P5E_CPU0_P1_TX_C_DP<9>
J 0
(-6690 2960);
DISPLAY 0.659574 (-6690 2960);
PAINT MONO (-6690 2960);
DISPLAY INVISIBLE (-6690 2960);
FORCEPROP 1 LASTPIN (-6700 2950) BN 9
J 0
(-6712 2958);
DISPLAY 0.680851 (-6712 2958);
PAINT GREEN (-6712 2958);
FORCEPROP 2 LAST CDS_LIB standard
J 0
(-6650 2950);
DISPLAY INVISIBLE (-6650 2950);
FORCEPROP 1 LAST BODY_TYPE PLUMBING
J 0
(-6650 3000);
DISPLAY 0.872340 (-6650 3000);
PAINT GREEN (-6650 3000);
DISPLAY INVISIBLE (-6650 3000);
FORCEPROP 1 LAST HDL_TAP TRUE
J 0
(-6325 2825);
DISPLAY 0.872340 (-6325 2825);
DISPLAY INVISIBLE (-6325 2825);
FORCEPROP 1 LAST PATH I5
J 0
(-6652 2950);
DISPLAY 0.872340 (-6652 2950);
PAINT GREEN (-6652 2950);
DISPLAY INVISIBLE (-6652 2950);
FORCEADD TAP..1
(-6850 3400);
FORCEPROP 3 LASTPIN (-6900 3400) SIG_NAME P5E_CPU0_P1_TX_C_DN<10>
J 0
(-6890 3410);
DISPLAY 0.659574 (-6890 3410);
PAINT MONO (-6890 3410);
DISPLAY INVISIBLE (-6890 3410);
FORCEPROP 1 LASTPIN (-6900 3400) BN 10
J 0
(-6912 3408);
DISPLAY 0.680851 (-6912 3408);
PAINT GREEN (-6912 3408);
FORCEPROP 2 LAST CDS_LIB standard
J 0
(-6850 3400);
DISPLAY INVISIBLE (-6850 3400);
FORCEPROP 1 LAST BODY_TYPE PLUMBING
J 0
(-6850 3450);
DISPLAY 0.872340 (-6850 3450);
PAINT GREEN (-6850 3450);
DISPLAY INVISIBLE (-6850 3450);
FORCEPROP 1 LAST HDL_TAP TRUE
J 0
(-6525 3275);
DISPLAY 0.872340 (-6525 3275);
DISPLAY INVISIBLE (-6525 3275);
FORCEPROP 1 LAST PATH I6
J 0
(-6852 3400);
DISPLAY 0.872340 (-6852 3400);
PAINT GREEN (-6852 3400);
DISPLAY INVISIBLE (-6852 3400);
FORCEADD TAP..1
(-6650 3300);
FORCEPROP 3 LASTPIN (-6700 3300) SIG_NAME P5E_CPU0_P1_TX_C_DP<10>
J 0
(-6690 3310);
DISPLAY 0.659574 (-6690 3310);
PAINT MONO (-6690 3310);
DISPLAY INVISIBLE (-6690 3310);
FORCEPROP 1 LASTPIN (-6700 3300) BN 10
J 0
(-6712 3308);
DISPLAY 0.680851 (-6712 3308);
PAINT GREEN (-6712 3308);
FORCEPROP 2 LAST CDS_LIB standard
J 0
(-6650 3300);
DISPLAY INVISIBLE (-6650 3300);
FORCEPROP 1 LAST BODY_TYPE PLUMBING
J 0
(-6650 3350);
DISPLAY 0.872340 (-6650 3350);
PAINT GREEN (-6650 3350);
DISPLAY INVISIBLE (-6650 3350);
FORCEPROP 1 LAST HDL_TAP TRUE
J 0
(-6325 3175);
DISPLAY 0.872340 (-6325 3175);
DISPLAY INVISIBLE (-6325 3175);
FORCEPROP 1 LAST PATH I7
J 0
(-6652 3300);
DISPLAY 0.872340 (-6652 3300);
PAINT GREEN (-6652 3300);
DISPLAY INVISIBLE (-6652 3300);
FORCEADD TAP..1
(-6650 3650);
FORCEPROP 3 LASTPIN (-6700 3650) SIG_NAME P5E_CPU0_P1_TX_C_DP<11>
J 0
(-6690 3660);
DISPLAY 0.659574 (-6690 3660);
PAINT MONO (-6690 3660);
DISPLAY INVISIBLE (-6690 3660);
FORCEPROP 1 LASTPIN (-6700 3650) BN 11
J 0
(-6712 3658);
DISPLAY 0.680851 (-6712 3658);
PAINT GREEN (-6712 3658);
FORCEPROP 2 LAST CDS_LIB standard
J 0
(-6650 3650);
DISPLAY INVISIBLE (-6650 3650);
FORCEPROP 1 LAST BODY_TYPE PLUMBING
J 0
(-6650 3700);
DISPLAY 0.872340 (-6650 3700);
PAINT GREEN (-6650 3700);
DISPLAY INVISIBLE (-6650 3700);
FORCEPROP 1 LAST HDL_TAP TRUE
J 0
(-6325 3525);
DISPLAY 0.872340 (-6325 3525);
DISPLAY INVISIBLE (-6325 3525);
FORCEPROP 1 LAST PATH I8
J 0
(-6652 3650);
DISPLAY 0.872340 (-6652 3650);
PAINT GREEN (-6652 3650);
DISPLAY INVISIBLE (-6652 3650);
FORCEADD TAP..1
(-6850 3750);
FORCEPROP 3 LASTPIN (-6900 3750) SIG_NAME P5E_CPU0_P1_TX_C_DN<11>
J 0
(-6890 3760);
DISPLAY 0.659574 (-6890 3760);
PAINT MONO (-6890 3760);
DISPLAY INVISIBLE (-6890 3760);
FORCEPROP 1 LASTPIN (-6900 3750) BN 11
J 0
(-6912 3758);
DISPLAY 0.680851 (-6912 3758);
PAINT GREEN (-6912 3758);
FORCEPROP 2 LAST CDS_LIB standard
J 0
(-6850 3750);
DISPLAY INVISIBLE (-6850 3750);
FORCEPROP 1 LAST BODY_TYPE PLUMBING
J 0
(-6850 3800);
DISPLAY 0.872340 (-6850 3800);
PAINT GREEN (-6850 3800);
DISPLAY INVISIBLE (-6850 3800);
FORCEPROP 1 LAST HDL_TAP TRUE
J 0
(-6525 3625);
DISPLAY 0.872340 (-6525 3625);
DISPLAY INVISIBLE (-6525 3625);
FORCEPROP 1 LAST PATH I9
J 0
(-6852 3750);
DISPLAY 0.872340 (-6852 3750);
PAINT GREEN (-6852 3750);
DISPLAY INVISIBLE (-6852 3750);
FORCEADD QUANTA_TITLE_BLOCK_C..1
(0 0);
FORCEPROP 0 LAST CDS_CON_LAST_MODIFIED Thu Sep 14 16:12:51 2023
J 0
(-1885 15);
DISPLAY INVISIBLE (-1885 15);
FORCEPROP 1 LAST CUSTOM_TXT_CDS <CON_LAST_MODIFIED>
J 0
(-1885 15);
DISPLAY 0.978723 (-1885 15);
FORCEPROP 2 LAST CUSTOM_TXT_CDS <XR_PAGE_TITLE>
J 0
(-7890 5250);
DISPLAY 0.638298 (-7890 5250);
PAINT PINK (-7890 5250);
DISPLAY INVISIBLE (-7890 5250);
FORCEPROP 1 LAST CUSTOM_TXT_CDS <NAME_2>
J 0
(-3175 50);
FORCEPROP 1 LAST CUSTOM_TXT_CDS <NAME_1>
J 0
(-3175 175);
FORCEPROP 1 LAST CUSTOM_TXT_CDS <Q_NUMBER>
J 0
(-1403 103);
DISPLAY 1.212766 (-1403 103);
FORCEPROP 1 LAST CUSTOM_TXT_CDS <Q_PROJ>
J 0
(-2382 102);
DISPLAY 1.212766 (-2382 102);
FORCEPROP 1 LAST CUSTOM_TXT_CDS <Q_REV>
J 0
(-184 103);
DISPLAY 1.212766 (-184 103);
FORCEPROP 1 LAST CUSTOM_TXT_CDS <CON_PAGE_NUM> OF <CON_TOTAL_PAGES>
J 0
(-446 18);
DISPLAY 0.978723 (-446 18);
FORCEPROP 1 LAST Q_TITLE RETIMER_CPU0_P1(1)
J 0
(-9366 26);
DISPLAY 2.446809 (-9366 26);
PAINT GREEN (-9366 26);
FORCEPROP 2 LAST PAGE_BORDER TRUE
J 0
(-7890 5250);
DISPLAY 0.638298 (-7890 5250);
PAINT PINK (-7890 5250);
DISPLAY INVISIBLE (-7890 5250);
FORCEPROP 2 LAST CDS_LIB pure_quanta
J 0
(0 0);
DISPLAY INVISIBLE (0 0);
FORCEPROP 1 LAST CDS_LMAN_SYM_OUTLINE -9475,6775,100,-125
J 0
(0 0);
DISPLAY 0.468085 (0 0);
PAINT GREEN (0 0);
DISPLAY INVISIBLE (0 0);
FORCEPROP 2 LAST CDS_XR_PAGE_TITLE CR-284 : @T6G_MB_LIB.T6G(SCH_1):PAGE284
J 0
(-7890 5250);
DISPLAY 0.638298 (-7890 5250);
PAINT PINK (-7890 5250);
DISPLAY INVISIBLE (-7890 5250);
FORCEPROP 1 LAST Q_DEPT BU9
J 1
(-3763 49);
DISPLAY 1.957447 (-3763 49);
PAINT GREEN (-3763 49);
DISPLAY INVISIBLE (-3763 49);
FORCEPROP 1 LAST COMMENT_BODY TRUE
J 0
(12 -13);
DISPLAY 0.978723 (12 -13);
PAINT GREEN (12 -13);
DISPLAY INVISIBLE (12 -13);
WIRE 17 -1 (-6800 5175)(-6800 4725);
WIRE 17 -1 (-6800 5175)(-5700 5175);
FORCEPROP 2 LAST SIG_NAME P5E_CPU0_P1_TX_C_DN<15:8>
J 0
(-6535 5185);
DISPLAY 0.680851 (-6535 5185);
PAINT WHITE (-6535 5185);
WIRE 17 -1 (-6600 5075)(-6600 4825);
WIRE 17 -1 (-6600 5075)(-5700 5075);
FORCEPROP 2 LAST SIG_NAME P5E_CPU0_P1_TX_C_DP<15:8>
J 0
(-6535 5085);
DISPLAY 0.680851 (-6535 5085);
PAINT WHITE (-6535 5085);
WIRE 17 -1 (-6600 4825)(-6600 4375);
WIRE 17 -1 (-6600 4375)(-6600 4025);
WIRE 17 -1 (-6600 3675)(-6600 4025);
WIRE 17 -1 (-6600 3675)(-6600 3325);
WIRE 17 -1 (-6600 3325)(-6600 2975);
WIRE 17 -1 (-6600 2975)(-6600 2625);
WIRE 17 -1 (-6800 3425)(-6800 3075);
WIRE 17 -1 (-6800 3775)(-6800 3425);
WIRE 17 -1 (-6800 3075)(-6800 2725);
WIRE 17 -1 (-6800 3775)(-6800 4125);
WIRE 17 -1 (-6800 4475)(-6800 4125);
WIRE 17 -1 (-6800 4725)(-6800 4475);
WIRE 17 -1 (-1975 3025)(-1975 2575);
WIRE 17 -1 (-1975 3275)(-1975 3025);
WIRE 17 -1 (-1975 3625)(-1975 3275);
WIRE 17 -1 (-1975 3625)(-1975 3975);
WIRE 17 -1 (-1975 4325)(-1975 3975);
WIRE 17 -1 (-1975 4675)(-1975 4325);
WIRE 17 -1 (-1975 5025)(-1975 4675);
WIRE 17 -1 (-1975 5025)(-1075 5025);
FORCEPROP 2 LAST SIG_NAME P5E_CPU0_P1_TX_C_DP<7:0>
J 0
(-1910 5035);
DISPLAY 0.680851 (-1910 5035);
PAINT WHITE (-1910 5035);
WIRE 17 -1 (-2175 3725)(-2175 3375);
WIRE 17 -1 (-2175 3725)(-2175 4075);
WIRE 17 -1 (-2175 3375)(-2175 2925);
WIRE 17 -1 (-2175 2925)(-2175 2675);
WIRE 17 -1 (-2175 4425)(-2175 4075);
WIRE 17 -1 (-2175 4775)(-2175 4425);
WIRE 17 -1 (-2175 5125)(-2175 4775);
WIRE 17 -1 (-2175 5125)(-1075 5125);
FORCEPROP 2 LAST SIG_NAME P5E_CPU0_P1_TX_C_DN<7:0>
J 0
(-1910 5135);
DISPLAY 0.680851 (-1910 5135);
PAINT WHITE (-1910 5135);
WIRE 16 -1 (-2800 4750)(-2275 4750);
WIRE 16 -1 (-2800 3250)(-2075 3250);
WIRE 16 -1 (-2275 2900)(-2800 2900);
WIRE 16 -1 (-2800 4050)(-2275 4050);
WIRE 16 -1 (-2800 3700)(-2275 3700);
WIRE 16 -1 (-2800 4400)(-2275 4400);
WIRE 16 -1 (-2800 2650)(-2275 2650);
WIRE 16 -1 (-2800 5100)(-2275 5100);
WIRE 16 -1 (-2800 3350)(-2275 3350);
WIRE 16 -1 (-7425 4000)(-6700 4000);
WIRE 16 -1 (-2800 3000)(-2075 3000);
WIRE 16 -1 (-2800 3600)(-2075 3600);
WIRE 16 -1 (-2800 4650)(-2075 4650);
WIRE 16 -1 (-2800 4300)(-2075 4300);
WIRE 16 -1 (-2800 3950)(-2075 3950);
WIRE 16 -1 (-2800 5000)(-2075 5000);
WIRE 16 -1 (-2800 2550)(-2075 2550);
WIRE 16 -1 (-7425 3650)(-6700 3650);
WIRE 16 -1 (-7425 2600)(-6700 2600);
WIRE 16 -1 (-7425 2950)(-6700 2950);
WIRE 16 -1 (-7425 4450)(-6900 4450);
WIRE 16 -1 (-7425 4100)(-6900 4100);
WIRE 16 -1 (-7425 5150)(-6900 5150);
WIRE 16 -1 (-7425 3750)(-6900 3750);
WIRE 16 -1 (-7425 3400)(-6900 3400);
WIRE 16 -1 (-7425 2700)(-6900 2700);
WIRE 16 -1 (-7425 3050)(-6900 3050);
WIRE 16 -1 (-7425 3300)(-6700 3300);
WIRE 16 -1 (-7425 4350)(-6700 4350);
WIRE 16 -1 (-7425 5050)(-6700 5050);
WIRE 16 -1 (-7425 4800)(-6700 4800);
WIRE 16 -1 (-7425 4700)(-6900 4700);
FORCENOTE
P/N SWAP
(-6450 3700) 0;
DISPLAY LEFT (-6450 3700);
DISPLAY 1.021277 (-6450 3700);
FORCENOTE
P/N SWAP
(-6500 4025) 0;
DISPLAY LEFT (-6500 4025);
DISPLAY 1.021277 (-6500 4025);
FORCENOTE
P/N SWAP
(-1775 3250) 0;
DISPLAY LEFT (-1775 3250);
DISPLAY 1.021277 (-1775 3250);
FORCENOTE
P/N SWAP
(-1825 3975) 0;
DISPLAY LEFT (-1825 3975);
DISPLAY 1.021277 (-1825 3975);
FORCENOTE
P/N SWAP
(-1825 3625) 0;
DISPLAY LEFT (-1825 3625);
DISPLAY 1.021277 (-1825 3625);
FORCENOTE
P5E_CPU0_P1_TX_C_DP/DN<0-15> LANE REVERSAL
(-8900 6350) 0;
DISPLAY LEFT (-8900 6350);
DISPLAY 2.000000 (-8900 6350);
FORCENOTE
CPU TO RETIMER
(-8300 1750) 0;
DISPLAY LEFT (-8300 1750);
DISPLAY 3.148936 (-8300 1750);
FORCENOTE
CPU TO RETIMER
(-3700 1750) 0;
DISPLAY LEFT (-3700 1750);
DISPLAY 3.148936 (-3700 1750);
FORCENOTE
P/N SWAP
(-1750 2600) 0;
DISPLAY LEFT (-1750 2600);
DISPLAY 1.021277 (-1750 2600);
FORCENOTE
P/N SWAP
(-6475 2625) 0;
DISPLAY LEFT (-6475 2625);
DISPLAY 1.021277 (-6475 2625);
FORCENOTE
P/N SWAP
(-6475 2950) 0;
DISPLAY LEFT (-6475 2950);
DISPLAY 1.021277 (-6475 2950);
FORCENOTE
P/N SWAP
(-6450 3325) 0;
DISPLAY LEFT (-6450 3325);
DISPLAY 1.021277 (-6450 3325);
FORCENOTE
P/N SWAP
(-1825 4325) 0;
DISPLAY LEFT (-1825 4325);
DISPLAY 1.021277 (-1825 4325);
FORCENOTE
P/N SWAP
(-1775 4925) 0;
DISPLAY LEFT (-1775 4925);
DISPLAY 1.021277 (-1775 4925);
FORCENOTE
P/N SWAP
(-1800 4700) 0;
DISPLAY LEFT (-1800 4700);
DISPLAY 1.021277 (-1800 4700);
FORCENOTE
P/N SWAP
(-6500 4375) 0;
DISPLAY LEFT (-6500 4375);
DISPLAY 1.021277 (-6500 4375);
FORCENOTE
P/N SWAP
(-6500 4975) 0;
DISPLAY LEFT (-6500 4975);
DISPLAY 1.021277 (-6500 4975);
QUIT
